#ISCELL
  mstr_misc dns *
  *
#ISCELL
  pure_quanta quanta_title_block_c *
  *
#ISCELL
  standard offpage *
  page139_i1
#ISCELL
  logical_power universal_power *
  page139_i10
#ISCELL
  logical_power universal_gnd *
  page139_i100
#ISCELL
  logical_power universal_gnd *
  page139_i101
#ISCELL
  logical_power universal_gnd *
  page139_i102
#CELL
  pure_quanta q_res *
  page139_i107
#CELL
  pure_quanta q_res *
  page139_i108
#CELL
  pure_quanta q_res *
  page139_i109
#ISCELL
  logical_power universal_gnd *
  page139_i11
#CELL
  pure_quanta q_res *
  page139_i110
#ISCELL
  standard offpage *
  page139_i12
#CELL
  pure_quanta q_res *
  page139_i13
#CELL
  pure_quanta q_res *
  page139_i14
#ISCELL
  logical_power universal_power *
  page139_i15
#ISCELL
  logical_power universal_gnd *
  page139_i16
#CELL
  pure_quanta mosfet_nch_dual *
  page139_i17
#CELL
  pure_quanta q_res *
  page139_i18
#ISCELL
  logical_power universal_power *
  page139_i19
#CELL
  pure_quanta q_res *
  page139_i2
#ISCELL
  logical_power universal_gnd *
  page139_i20
#CELL
  pure_quanta mosfet_nch_dual *
  page139_i21
#CELL
  pure_quanta mosfet_nch_dual *
  page139_i22
#CELL
  pure_quanta q_res *
  page139_i23
#ISCELL
  logical_power universal_power *
  page139_i24
#CELL
  pure_quanta mosfet_nch_dual *
  page139_i25
#ISCELL
  logical_power universal_gnd *
  page139_i26
#CELL
  pure_quanta q_res *
  page139_i27
#CELL
  pure_quanta mosfet_nch_dual *
  page139_i28
#CELL
  pure_quanta mosfet_nch_dual *
  page139_i29
#ISCELL
  logical_power universal_gnd *
  page139_i3
#ISCELL
  logical_power universal_power *
  page139_i30
#ISCELL
  logical_power universal_gnd *
  page139_i31
#ISCELL
  logical_power universal_gnd *
  page139_i32
#CELL
  pure_quanta q_cap *
  page139_i33
#ISCELL
  logical_power universal_gnd *
  page139_i34
#CELL
  pure_quanta q_res *
  page139_i35
#ISCELL
  logical_power universal_power *
  page139_i36
#ISCELL
  logical_power universal_gnd *
  page139_i37
#ISCELL
  standard offpage *
  page139_i38
#CELL
  pure_quanta q_res *
  page139_i39
#CELL
  pure_quanta q_res *
  page139_i4
#ISCELL
  logical_power universal_power *
  page139_i40
#ISCELL
  logical_power universal_gnd *
  page139_i41
#CELL
  pure_quanta q_cap *
  page139_i42
#ISCELL
  logical_power universal_gnd *
  page139_i43
#CELL
  pure_quanta q_cap *
  page139_i44
#ISCELL
  standard offpage *
  page139_i45
#ISCELL
  standard offpage *
  page139_i46
#CELL
  pure_quanta q_res *
  page139_i47
#ISCELL
  logical_power universal_power *
  page139_i48
#ISCELL
  logical_power universal_power *
  page139_i49
#ISCELL
  standard offpage *
  page139_i5
#CELL
  pure_quanta q_res *
  page139_i50
#ISCELL
  standard offpage *
  page139_i51
#CELL
  pure_quanta q_cap *
  page139_i52
#ISCELL
  logical_power universal_gnd *
  page139_i53
#ISCELL
  logical_power universal_gnd *
  page139_i54
#CELL
  pure_quanta mosfet_nch_dual *
  page139_i55
#ISCELL
  logical_power universal_power *
  page139_i56
#CELL
  pure_quanta q_res *
  page139_i57
#ISCELL
  logical_power universal_power *
  page139_i58
#ISCELL
  logical_power universal_power *
  page139_i6
#ISCELL
  logical_power universal_gnd *
  page139_i60
#CELL
  pure_quanta mosfet_nch_dual *
  page139_i61
#CELL
  pure_quanta q_res *
  page139_i62
#ISCELL
  logical_power universal_gnd *
  page139_i63
#ISCELL
  standard offpage *
  page139_i64
#ISCELL
  logical_power universal_gnd *
  page139_i7
#CELL
  pure_quanta q_res *
  page139_i8
#CELL
  pure_quanta q_res *
  page139_i85
#CELL
  pure_quanta 74lvc2g17gw *
  page139_i86
#CELL
  pure_quanta q_res *
  page139_i87
#ISCELL
  logical_power universal_power *
  page139_i88
#CELL
  pure_quanta q_res *
  page139_i89
#CELL
  pure_quanta q_res *
  page139_i9
#ISCELL
  logical_power universal_gnd *
  page139_i90
#ISCELL
  standard offpage *
  page139_i91
#ISCELL
  logical_power universal_gnd *
  page139_i92
#CELL
  pure_quanta q_cap *
  page139_i93
#ISCELL
  logical_power universal_power *
  page139_i94
#ISCELL
  standard offpage *
  page139_i95
#ISCELL
  logical_power universal_power *
  page139_i96
#CELL
  pure_quanta q_res *
  page139_i98
#CELL
  pure_quanta q_res *
  page139_i99
